(kicad_pcb
	(version 20260206)
	(generator "pcbnew")
	(generator_version "10.0")
	(general
		(thickness 1.6)
		(legacy_teardrops no)
	)
	(paper "A4")
	(title_block
		(title "01162023_DA0F0TEBIF0_F0T_Expander_BD_F_brd_V02_OCP.brd")
		(comment 1 "Grand Teton / footprints 13-19 of 9728")
	)
	(layers
		(0 "F.Cu" signal "TOP")
		(4 "In1.Cu" signal "GND")
		(6 "In2.Cu" signal "VCC")
		(8 "In3.Cu" signal "VCC1")
		(10 "In4.Cu" signal "GND1")
		(12 "In5.Cu" signal "IN1")
		(14 "In6.Cu" signal "GND2")
		(16 "In7.Cu" signal "IN2")
		(18 "In8.Cu" signal "GND3")
		(20 "In9.Cu" signal "IN3")
		(22 "In10.Cu" signal "GND4")
		(24 "In11.Cu" signal "IN4")
		(26 "In12.Cu" signal "GND5")
		(28 "In13.Cu" signal "IN5")
		(30 "In14.Cu" signal "GND6")
		(32 "In15.Cu" signal "IN6")
		(34 "In16.Cu" signal "GND7")
		(2 "B.Cu" signal "BOTTOM")
		(9 "F.Adhes" user "F.Adhesive")
		(11 "B.Adhes" user "B.Adhesive")
		(13 "F.Paste" user "Package Geometry/Pastemask Top")
		(15 "B.Paste" user "Package Geometry/Pastemask Bottom")
		(5 "F.SilkS" user "Ref Des/Silkscreen Top")
		(7 "B.SilkS" user "Ref Des/Silkscreen Bottom")
		(1 "F.Mask" user "Board Geometry/Soldermask Top")
		(3 "B.Mask" user "Board Geometry/Soldermask Bottom")
		(17 "Dwgs.User" user "User.Drawings")
		(19 "Cmts.User" user "User.Comments")
		(21 "Eco1.User" user "User.Eco1")
		(23 "Eco2.User" user "User.Eco2")
		(25 "Edge.Cuts" user "Board Geometry/Outline")
		(27 "Margin" user)
		(31 "F.CrtYd" user "Package Geometry/Place Bound Top")
		(29 "B.CrtYd" user "Package Geometry/Place Bound Bottom")
		(35 "F.Fab" user "Ref Des/Assembly Top")
		(33 "B.Fab" user "Ref Des/Assembly Bottom")
	)
	(footprint ""
		(layer "F.Cu")
		(at 59.421268 -393.16279 -90)
		(property "Reference" "C4038"
			(at 0 0 270)
			(layer "F.SilkS")
			(hide yes)
			(effects
				(font
					(size 1.27 1.27)
				)
			)
		)
		(property "Value" ""
			(at 0 0 270)
			(layer "F.Fab")
			(effects
				(font
					(size 1.27 1.27)
				)
			)
		)
		(duplicate_pad_numbers_are_jumpers no)
		(fp_line
			(start -0.7874 0.4064)
			(end -0.7874 -0.4064)
			(stroke
				(width 0.1524)
				(type default)
			)
			(layer "F.SilkS")
		)
		(fp_line
			(start 0.7874 0.4064)
			(end -0.7874 0.4064)
			(stroke
				(width 0.1524)
				(type default)
			)
			(layer "F.SilkS")
		)
		(fp_line
			(start -0.7874 -0.4064)
			(end 0.7874 -0.4064)
			(stroke
				(width 0.1524)
				(type default)
			)
			(layer "F.SilkS")
		)
		(fp_line
			(start 0.7874 -0.4064)
			(end 0.7874 0.4064)
			(stroke
				(width 0.1524)
				(type default)
			)
			(layer "F.SilkS")
		)
		(fp_line
			(start -0.67945 0.3048)
			(end -0.67945 -0.305054)
			(stroke
				(width 0.1)
				(type default)
			)
			(layer "F.Fab")
		)
		(fp_line
			(start -0.12065 0.3048)
			(end -0.67945 0.3048)
			(stroke
				(width 0.1)
				(type default)
			)
			(layer "F.Fab")
		)
		(fp_line
			(start 0.120396 0.3048)
			(end 0.120396 0.2794)
			(stroke
				(width 0.1)
				(type default)
			)
			(layer "F.Fab")
		)
		(fp_line
			(start 0.67945 0.3048)
			(end 0.120396 0.3048)
			(stroke
				(width 0.1)
				(type default)
			)
			(layer "F.Fab")
		)
		(fp_line
			(start -0.12065 0.2794)
			(end -0.12065 0.3048)
			(stroke
				(width 0.1)
				(type default)
			)
			(layer "F.Fab")
		)
		(fp_line
			(start 0.120396 0.2794)
			(end -0.12065 0.2794)
			(stroke
				(width 0.1)
				(type default)
			)
			(layer "F.Fab")
		)
		(fp_line
			(start -0.12065 -0.2794)
			(end 0.12065 -0.2794)
			(stroke
				(width 0.1)
				(type default)
			)
			(layer "F.Fab")
		)
		(fp_line
			(start 0.12065 -0.2794)
			(end 0.12065 -0.3048)
			(stroke
				(width 0.1)
				(type default)
			)
			(layer "F.Fab")
		)
		(fp_line
			(start 0.12065 -0.3048)
			(end 0.67945 -0.3048)
			(stroke
				(width 0.1)
				(type default)
			)
			(layer "F.Fab")
		)
		(fp_line
			(start 0.67945 -0.3048)
			(end 0.67945 0.3048)
			(stroke
				(width 0.1)
				(type default)
			)
			(layer "F.Fab")
		)
		(fp_line
			(start -0.67945 -0.305054)
			(end -0.12065 -0.305054)
			(stroke
				(width 0.1)
				(type default)
			)
			(layer "F.Fab")
		)
		(fp_line
			(start -0.12065 -0.305054)
			(end -0.12065 -0.2794)
			(stroke
				(width 0.1)
				(type default)
			)
			(layer "F.Fab")
		)
		(pad "1" smd circle
			(at -0.40005 0 270)
			(size 0 0)
			(layers "F.Cu" "F.Mask" "F.Paste")
			(net "GND")
		)
		(pad "2" smd circle
			(at 0.40005 0 270)
			(size 0 0)
			(layers "F.Cu" "F.Mask" "F.Paste")
			(net "RST_GPU_FPGA_PEX_RST_N")
		)
	)
	(footprint ""
		(layer "F.Cu")
		(at 234.499912 -373.9134 180)
		(property "Reference" "PR36"
			(at 0 0 180)
			(layer "F.SilkS")
			(hide yes)
			(effects
				(font
					(size 1.27 1.27)
				)
			)
		)
		(property "Value" ""
			(at 0 0 180)
			(layer "F.Fab")
			(effects
				(font
					(size 1.27 1.27)
				)
			)
		)
		(duplicate_pad_numbers_are_jumpers no)
		(fp_line
			(start 0.7874 0.4064)
			(end -0.7874 0.4064)
			(stroke
				(width 0.1524)
				(type default)
			)
			(layer "F.SilkS")
		)
		(fp_line
			(start 0.7874 -0.4064)
			(end 0.7874 0.4064)
			(stroke
				(width 0.1524)
				(type default)
			)
			(layer "F.SilkS")
		)
		(fp_line
			(start -0.7874 0.4064)
			(end -0.7874 -0.4064)
			(stroke
				(width 0.1524)
				(type default)
			)
			(layer "F.SilkS")
		)
		(fp_line
			(start -0.7874 -0.4064)
			(end 0.7874 -0.4064)
			(stroke
				(width 0.1524)
				(type default)
			)
			(layer "F.SilkS")
		)
		(fp_line
			(start 0.67945 0.3048)
			(end 0.120396 0.3048)
			(stroke
				(width 0.1)
				(type default)
			)
			(layer "F.Fab")
		)
		(fp_line
			(start 0.67945 -0.3048)
			(end 0.67945 0.3048)
			(stroke
				(width 0.1)
				(type default)
			)
			(layer "F.Fab")
		)
		(fp_line
			(start 0.12065 -0.2794)
			(end 0.12065 -0.3048)
			(stroke
				(width 0.1)
				(type default)
			)
			(layer "F.Fab")
		)
		(fp_line
			(start 0.12065 -0.3048)
			(end 0.67945 -0.3048)
			(stroke
				(width 0.1)
				(type default)
			)
			(layer "F.Fab")
		)
		(fp_line
			(start 0.120396 0.3048)
			(end 0.120396 0.2794)
			(stroke
				(width 0.1)
				(type default)
			)
			(layer "F.Fab")
		)
		(fp_line
			(start 0.120396 0.2794)
			(end -0.12065 0.2794)
			(stroke
				(width 0.1)
				(type default)
			)
			(layer "F.Fab")
		)
		(fp_line
			(start -0.12065 0.3048)
			(end -0.67945 0.3048)
			(stroke
				(width 0.1)
				(type default)
			)
			(layer "F.Fab")
		)
		(fp_line
			(start -0.12065 0.2794)
			(end -0.12065 0.3048)
			(stroke
				(width 0.1)
				(type default)
			)
			(layer "F.Fab")
		)
		(fp_line
			(start -0.12065 -0.2794)
			(end 0.12065 -0.2794)
			(stroke
				(width 0.1)
				(type default)
			)
			(layer "F.Fab")
		)
		(fp_line
			(start -0.12065 -0.305054)
			(end -0.12065 -0.2794)
			(stroke
				(width 0.1)
				(type default)
			)
			(layer "F.Fab")
		)
		(fp_line
			(start -0.67945 0.3048)
			(end -0.67945 -0.305054)
			(stroke
				(width 0.1)
				(type default)
			)
			(layer "F.Fab")
		)
		(fp_line
			(start -0.67945 -0.305054)
			(end -0.12065 -0.305054)
			(stroke
				(width 0.1)
				(type default)
			)
			(layer "F.Fab")
		)
		(pad "1" smd circle
			(at -0.40005 0 180)
			(size 0 0)
			(layers "F.Cu" "F.Mask" "F.Paste")
			(net "AGND_HSC")
		)
		(pad "2" smd circle
			(at 0.40005 0 180)
			(size 0 0)
			(layers "F.Cu" "F.Mask" "F.Paste")
			(net "HSC_MODE_2")
		)
	)
	(footprint ""
		(layer "F.Cu")
		(at 430.961546 -145.311114 180)
		(property "Reference" "C646"
			(at 0 0 180)
			(layer "F.SilkS")
			(hide yes)
			(effects
				(font
					(size 1.27 1.27)
				)
			)
		)
		(property "Value" ""
			(at 0 0 180)
			(layer "F.Fab")
			(effects
				(font
					(size 1.27 1.27)
				)
			)
		)
		(duplicate_pad_numbers_are_jumpers no)
		(fp_line
			(start 0.299974 0.150114)
			(end -0.299974 0.150114)
			(stroke
				(width 0.1)
				(type default)
			)
			(layer "F.Fab")
		)
		(fp_line
			(start 0.299974 -0.150114)
			(end 0.299974 0.150114)
			(stroke
				(width 0.1)
				(type default)
			)
			(layer "F.Fab")
		)
		(fp_line
			(start -0.299974 0.150114)
			(end -0.299974 -0.150114)
			(stroke
				(width 0.1)
				(type default)
			)
			(layer "F.Fab")
		)
		(fp_line
			(start -0.299974 -0.150114)
			(end 0.299974 -0.150114)
			(stroke
				(width 0.1)
				(type default)
			)
			(layer "F.Fab")
		)
		(pad "1" smd rect
			(at -0.2667 0 180)
			(size 0.3048 0.381)
			(layers "F.Cu" "F.Mask" "F.Paste")
			(net "P5E_PEX3_STN0_TX_DP<9>")
		)
		(pad "2" smd rect
			(at 0.2667 0 180)
			(size 0.3048 0.381)
			(layers "F.Cu" "F.Mask" "F.Paste")
			(net "P5E_PEX3_STN0_TX_C_DP<9>")
		)
	)
	(footprint ""
		(layer "F.Cu")
		(at 394.814552 -66.32194 90)
		(property "Reference" "R6011"
			(at 0 0 90)
			(layer "F.SilkS")
			(hide yes)
			(effects
				(font
					(size 1.27 1.27)
				)
			)
		)
		(property "Value" ""
			(at 0 0 90)
			(layer "F.Fab")
			(effects
				(font
					(size 1.27 1.27)
				)
			)
		)
		(duplicate_pad_numbers_are_jumpers no)
		(fp_line
			(start 0.7874 -0.4064)
			(end 0.7874 0.4064)
			(stroke
				(width 0.1524)
				(type default)
			)
			(layer "F.SilkS")
		)
		(fp_line
			(start -0.7874 -0.4064)
			(end 0.7874 -0.4064)
			(stroke
				(width 0.1524)
				(type default)
			)
			(layer "F.SilkS")
		)
		(fp_line
			(start 0.7874 0.4064)
			(end -0.7874 0.4064)
			(stroke
				(width 0.1524)
				(type default)
			)
			(layer "F.SilkS")
		)
		(fp_line
			(start -0.7874 0.4064)
			(end -0.7874 -0.4064)
			(stroke
				(width 0.1524)
				(type default)
			)
			(layer "F.SilkS")
		)
		(fp_line
			(start -0.12065 -0.305054)
			(end -0.12065 -0.2794)
			(stroke
				(width 0.1)
				(type default)
			)
			(layer "F.Fab")
		)
		(fp_line
			(start -0.67945 -0.305054)
			(end -0.12065 -0.305054)
			(stroke
				(width 0.1)
				(type default)
			)
			(layer "F.Fab")
		)
		(fp_line
			(start 0.67945 -0.3048)
			(end 0.67945 0.3048)
			(stroke
				(width 0.1)
				(type default)
			)
			(layer "F.Fab")
		)
		(fp_line
			(start 0.12065 -0.3048)
			(end 0.67945 -0.3048)
			(stroke
				(width 0.1)
				(type default)
			)
			(layer "F.Fab")
		)
		(fp_line
			(start 0.12065 -0.2794)
			(end 0.12065 -0.3048)
			(stroke
				(width 0.1)
				(type default)
			)
			(layer "F.Fab")
		)
		(fp_line
			(start -0.12065 -0.2794)
			(end 0.12065 -0.2794)
			(stroke
				(width 0.1)
				(type default)
			)
			(layer "F.Fab")
		)
		(fp_line
			(start 0.120396 0.2794)
			(end -0.12065 0.2794)
			(stroke
				(width 0.1)
				(type default)
			)
			(layer "F.Fab")
		)
		(fp_line
			(start -0.12065 0.2794)
			(end -0.12065 0.3048)
			(stroke
				(width 0.1)
				(type default)
			)
			(layer "F.Fab")
		)
		(fp_line
			(start 0.67945 0.3048)
			(end 0.120396 0.3048)
			(stroke
				(width 0.1)
				(type default)
			)
			(layer "F.Fab")
		)
		(fp_line
			(start 0.120396 0.3048)
			(end 0.120396 0.2794)
			(stroke
				(width 0.1)
				(type default)
			)
			(layer "F.Fab")
		)
		(fp_line
			(start -0.12065 0.3048)
			(end -0.67945 0.3048)
			(stroke
				(width 0.1)
				(type default)
			)
			(layer "F.Fab")
		)
		(fp_line
			(start -0.67945 0.3048)
			(end -0.67945 -0.305054)
			(stroke
				(width 0.1)
				(type default)
			)
			(layer "F.Fab")
		)
		(pad "1" smd circle
			(at -0.40005 0 90)
			(size 0 0)
			(layers "F.Cu" "F.Mask" "F.Paste")
			(net "SSD13_PWR_EN_R")
		)
		(pad "2" smd circle
			(at 0.40005 0 90)
			(size 0 0)
			(layers "F.Cu" "F.Mask" "F.Paste")
			(net "P12V_SSD13_CO_EN")
		)
	)
	(footprint ""
		(layer "F.Cu")
		(at 148.675852 -36.915598 -90)
		(property "Reference" "R5556"
			(at 0 0 270)
			(layer "F.SilkS")
			(hide yes)
			(effects
				(font
					(size 1.27 1.27)
				)
			)
		)
		(property "Value" ""
			(at 0 0 270)
			(layer "F.Fab")
			(effects
				(font
					(size 1.27 1.27)
				)
			)
		)
		(duplicate_pad_numbers_are_jumpers no)
		(fp_line
			(start -0.7874 0.4064)
			(end -0.7874 -0.4064)
			(stroke
				(width 0.1524)
				(type default)
			)
			(layer "F.SilkS")
		)
		(fp_line
			(start 0.7874 0.4064)
			(end -0.7874 0.4064)
			(stroke
				(width 0.1524)
				(type default)
			)
			(layer "F.SilkS")
		)
		(fp_line
			(start -0.7874 -0.4064)
			(end 0.7874 -0.4064)
			(stroke
				(width 0.1524)
				(type default)
			)
			(layer "F.SilkS")
		)
		(fp_line
			(start 0.7874 -0.4064)
			(end 0.7874 0.4064)
			(stroke
				(width 0.1524)
				(type default)
			)
			(layer "F.SilkS")
		)
		(fp_line
			(start -0.67945 0.3048)
			(end -0.67945 -0.305054)
			(stroke
				(width 0.1)
				(type default)
			)
			(layer "F.Fab")
		)
		(fp_line
			(start -0.12065 0.3048)
			(end -0.67945 0.3048)
			(stroke
				(width 0.1)
				(type default)
			)
			(layer "F.Fab")
		)
		(fp_line
			(start 0.120396 0.3048)
			(end 0.120396 0.2794)
			(stroke
				(width 0.1)
				(type default)
			)
			(layer "F.Fab")
		)
		(fp_line
			(start 0.67945 0.3048)
			(end 0.120396 0.3048)
			(stroke
				(width 0.1)
				(type default)
			)
			(layer "F.Fab")
		)
		(fp_line
			(start -0.12065 0.2794)
			(end -0.12065 0.3048)
			(stroke
				(width 0.1)
				(type default)
			)
			(layer "F.Fab")
		)
		(fp_line
			(start 0.120396 0.2794)
			(end -0.12065 0.2794)
			(stroke
				(width 0.1)
				(type default)
			)
			(layer "F.Fab")
		)
		(fp_line
			(start -0.12065 -0.2794)
			(end 0.12065 -0.2794)
			(stroke
				(width 0.1)
				(type default)
			)
			(layer "F.Fab")
		)
		(fp_line
			(start 0.12065 -0.2794)
			(end 0.12065 -0.3048)
			(stroke
				(width 0.1)
				(type default)
			)
			(layer "F.Fab")
		)
		(fp_line
			(start 0.12065 -0.3048)
			(end 0.67945 -0.3048)
			(stroke
				(width 0.1)
				(type default)
			)
			(layer "F.Fab")
		)
		(fp_line
			(start 0.67945 -0.3048)
			(end 0.67945 0.3048)
			(stroke
				(width 0.1)
				(type default)
			)
			(layer "F.Fab")
		)
		(fp_line
			(start -0.67945 -0.305054)
			(end -0.12065 -0.305054)
			(stroke
				(width 0.1)
				(type default)
			)
			(layer "F.Fab")
		)
		(fp_line
			(start -0.12065 -0.305054)
			(end -0.12065 -0.2794)
			(stroke
				(width 0.1)
				(type default)
			)
			(layer "F.Fab")
		)
		(pad "1" smd circle
			(at -0.40005 0 270)
			(size 0 0)
			(layers "F.Cu" "F.Mask" "F.Paste")
			(net "PRSNT_SSD5_R1_N")
		)
		(pad "2" smd circle
			(at 0.40005 0 270)
			(size 0 0)
			(layers "F.Cu" "F.Mask" "F.Paste")
			(net "PRSNT_SSD5_R_N")
		)
	)
	(footprint ""
		(layer "F.Cu")
		(at 247.897904 -122.780552)
		(property "Reference" "PC474"
			(at 0 0 0)
			(layer "F.SilkS")
			(hide yes)
			(effects
				(font
					(size 1.27 1.27)
				)
			)
		)
		(property "Value" ""
			(at 0 0 0)
			(layer "F.Fab")
			(effects
				(font
					(size 1.27 1.27)
				)
			)
		)
		(duplicate_pad_numbers_are_jumpers no)
		(fp_line
			(start -0.7874 -0.4064)
			(end 0.7874 -0.4064)
			(stroke
				(width 0.1524)
				(type default)
			)
			(layer "F.SilkS")
		)
		(fp_line
			(start -0.7874 0.4064)
			(end -0.7874 -0.4064)
			(stroke
				(width 0.1524)
				(type default)
			)
			(layer "F.SilkS")
		)
		(fp_line
			(start 0.7874 -0.4064)
			(end 0.7874 0.4064)
			(stroke
				(width 0.1524)
				(type default)
			)
			(layer "F.SilkS")
		)
		(fp_line
			(start 0.7874 0.4064)
			(end -0.7874 0.4064)
			(stroke
				(width 0.1524)
				(type default)
			)
			(layer "F.SilkS")
		)
		(fp_line
			(start -0.67945 -0.305054)
			(end -0.12065 -0.305054)
			(stroke
				(width 0.1)
				(type default)
			)
			(layer "F.Fab")
		)
		(fp_line
			(start -0.67945 0.3048)
			(end -0.67945 -0.305054)
			(stroke
				(width 0.1)
				(type default)
			)
			(layer "F.Fab")
		)
		(fp_line
			(start -0.12065 -0.305054)
			(end -0.12065 -0.2794)
			(stroke
				(width 0.1)
				(type default)
			)
			(layer "F.Fab")
		)
		(fp_line
			(start -0.12065 -0.2794)
			(end 0.12065 -0.2794)
			(stroke
				(width 0.1)
				(type default)
			)
			(layer "F.Fab")
		)
		(fp_line
			(start -0.12065 0.2794)
			(end -0.12065 0.3048)
			(stroke
				(width 0.1)
				(type default)
			)
			(layer "F.Fab")
		)
		(fp_line
			(start -0.12065 0.3048)
			(end -0.67945 0.3048)
			(stroke
				(width 0.1)
				(type default)
			)
			(layer "F.Fab")
		)
		(fp_line
			(start 0.120396 0.2794)
			(end -0.12065 0.2794)
			(stroke
				(width 0.1)
				(type default)
			)
			(layer "F.Fab")
		)
		(fp_line
			(start 0.120396 0.3048)
			(end 0.120396 0.2794)
			(stroke
				(width 0.1)
				(type default)
			)
			(layer "F.Fab")
		)
		(fp_line
			(start 0.12065 -0.3048)
			(end 0.67945 -0.3048)
			(stroke
				(width 0.1)
				(type default)
			)
			(layer "F.Fab")
		)
		(fp_line
			(start 0.12065 -0.2794)
			(end 0.12065 -0.3048)
			(stroke
				(width 0.1)
				(type default)
			)
			(layer "F.Fab")
		)
		(fp_line
			(start 0.67945 -0.3048)
			(end 0.67945 0.3048)
			(stroke
				(width 0.1)
				(type default)
			)
			(layer "F.Fab")
		)
		(fp_line
			(start 0.67945 0.3048)
			(end 0.120396 0.3048)
			(stroke
				(width 0.1)
				(type default)
			)
			(layer "F.Fab")
		)
		(pad "1" smd circle
			(at -0.40005 0)
			(size 0 0)
			(layers "F.Cu" "F.Mask" "F.Paste")
			(net "P3V3_AUX")
		)
		(pad "2" smd circle
			(at 0.40005 0)
			(size 0 0)
			(layers "F.Cu" "F.Mask" "F.Paste")
			(net "GND")
		)
	)
	(footprint ""
		(layer "F.Cu")
		(at 240.5888 -213.3854 -90)
		(property "Reference" "R6592"
			(at 0 0 270)
			(layer "F.SilkS")
			(hide yes)
			(effects
				(font
					(size 1.27 1.27)
				)
			)
		)
		(property "Value" ""
			(at 0 0 270)
			(layer "F.Fab")
			(effects
				(font
					(size 1.27 1.27)
				)
			)
		)
		(duplicate_pad_numbers_are_jumpers no)
		(fp_line
			(start -0.7874 0.4064)
			(end -0.7874 -0.4064)
			(stroke
				(width 0.1524)
				(type default)
			)
			(layer "F.SilkS")
		)
		(fp_line
			(start 0.7874 0.4064)
			(end -0.7874 0.4064)
			(stroke
				(width 0.1524)
				(type default)
			)
			(layer "F.SilkS")
		)
		(fp_line
			(start -0.7874 -0.4064)
			(end 0.7874 -0.4064)
			(stroke
				(width 0.1524)
				(type default)
			)
			(layer "F.SilkS")
		)
		(fp_line
			(start 0.7874 -0.4064)
			(end 0.7874 0.4064)
			(stroke
				(width 0.1524)
				(type default)
			)
			(layer "F.SilkS")
		)
		(fp_line
			(start -0.67945 0.3048)
			(end -0.67945 -0.305054)
			(stroke
				(width 0.1)
				(type default)
			)
			(layer "F.Fab")
		)
		(fp_line
			(start -0.12065 0.3048)
			(end -0.67945 0.3048)
			(stroke
				(width 0.1)
				(type default)
			)
			(layer "F.Fab")
		)
		(fp_line
			(start 0.120396 0.3048)
			(end 0.120396 0.2794)
			(stroke
				(width 0.1)
				(type default)
			)
			(layer "F.Fab")
		)
		(fp_line
			(start 0.67945 0.3048)
			(end 0.120396 0.3048)
			(stroke
				(width 0.1)
				(type default)
			)
			(layer "F.Fab")
		)
		(fp_line
			(start -0.12065 0.2794)
			(end -0.12065 0.3048)
			(stroke
				(width 0.1)
				(type default)
			)
			(layer "F.Fab")
		)
		(fp_line
			(start 0.120396 0.2794)
			(end -0.12065 0.2794)
			(stroke
				(width 0.1)
				(type default)
			)
			(layer "F.Fab")
		)
		(fp_line
			(start -0.12065 -0.2794)
			(end 0.12065 -0.2794)
			(stroke
				(width 0.1)
				(type default)
			)
			(layer "F.Fab")
		)
		(fp_line
			(start 0.12065 -0.2794)
			(end 0.12065 -0.3048)
			(stroke
				(width 0.1)
				(type default)
			)
			(layer "F.Fab")
		)
		(fp_line
			(start 0.12065 -0.3048)
			(end 0.67945 -0.3048)
			(stroke
				(width 0.1)
				(type default)
			)
			(layer "F.Fab")
		)
		(fp_line
			(start 0.67945 -0.3048)
			(end 0.67945 0.3048)
			(stroke
				(width 0.1)
				(type default)
			)
			(layer "F.Fab")
		)
		(fp_line
			(start -0.67945 -0.305054)
			(end -0.12065 -0.305054)
			(stroke
				(width 0.1)
				(type default)
			)
			(layer "F.Fab")
		)
		(fp_line
			(start -0.12065 -0.305054)
			(end -0.12065 -0.2794)
			(stroke
				(width 0.1)
				(type default)
			)
			(layer "F.Fab")
		)
		(pad "1" smd circle
			(at -0.40005 0 270)
			(size 0 0)
			(layers "F.Cu" "F.Mask" "F.Paste")
			(net "P1V8_PLL0_PEX1_SCALED")
		)
		(pad "2" smd circle
			(at 0.40005 0 270)
			(size 0 0)
			(layers "F.Cu" "F.Mask" "F.Paste")
			(net "GND")
		)
	)
)
